# T6G (Grand Teton) — schematic netlist excerpt (pin names and nets, part order shuffled) for the footprints in the layout excerpt that follows; sources: Cadence DE-HDL packaged netlist, KiCad conversion of 04192023_DAF0TMB3IC0_F0TG_MB_C_brd_V02_OCP.brd

C1274  Q_CAP  0.1UF 25V 10% X7R  pkg 0402  page 133 : A = P3V3_AUX ; B = GND
PR208  Q_RES  8.87K 1% EMPTY  pkg 0402LF  page 215 : A = GND ; B = PVDDCR_SOC_P1_LSET2

(kicad_pcb
	(version 20260206)
	(generator "pcbnew")
	(generator_version "10.0")
	(general
		(thickness 1.6)
		(legacy_teardrops no)
	)
	(paper "A4")
	(title_block
		(title "04192023_DAF0TMB3IC0_F0TG_MB_C_brd_V02_OCP.brd")
		(comment 1 "Grand Teton / footprints 2978-2979 of 8354")
	)
	(layers
		(0 "F.Cu" signal "TOP")
		(4 "In1.Cu" signal "GND")
		(6 "In2.Cu" signal "IN1")
		(8 "In3.Cu" signal "GND1")
		(10 "In4.Cu" signal "IN2")
		(12 "In5.Cu" signal "GND2")
		(14 "In6.Cu" signal "IN3")
		(16 "In7.Cu" signal "GND3")
		(18 "In8.Cu" signal "VCC")
		(20 "In9.Cu" signal "VCC1")
		(22 "In10.Cu" signal "GND4")
		(24 "In11.Cu" signal "IN4")
		(26 "In12.Cu" signal "GND5")
		(28 "In13.Cu" signal "IN5")
		(30 "In14.Cu" signal "GND6")
		(32 "In15.Cu" signal "IN6")
		(34 "In16.Cu" signal "GND7")
		(2 "B.Cu" signal "BOTTOM")
		(9 "F.Adhes" user "F.Adhesive")
		(11 "B.Adhes" user "B.Adhesive")
		(13 "F.Paste" user "Package Geometry/Pastemask Top")
		(15 "B.Paste" user "Package Geometry/Pastemask Bottom")
		(5 "F.SilkS" user "Ref Des/Silkscreen Top")
		(7 "B.SilkS" user "Ref Des/Silkscreen Bottom")
		(1 "F.Mask" user "Board Geometry/Soldermask Top")
		(3 "B.Mask" user "Board Geometry/Soldermask Bottom")
		(17 "Dwgs.User" user "User.Drawings")
		(19 "Cmts.User" user "User.Comments")
		(21 "Eco1.User" user "User.Eco1")
		(23 "Eco2.User" user "User.Eco2")
		(25 "Edge.Cuts" user "Board Geometry/Outline")
		(27 "Margin" user)
		(31 "F.CrtYd" user "Package Geometry/Place Bound Top")
		(29 "B.CrtYd" user "Package Geometry/Place Bound Bottom")
		(35 "F.Fab" user "Ref Des/Assembly Top")
		(33 "B.Fab" user "Ref Des/Assembly Bottom")
	)
	(footprint ""
		(layer "F.Cu")
		(at 125.270514 -159.980884)
		(property "Reference" "PR208"
			(at 0 0 0)
			(layer "F.SilkS")
			(hide yes)
			(effects
				(font
					(size 1.27 1.27)
				)
			)
		)
		(property "Value" ""
			(at 0 0 0)
			(layer "F.Fab")
			(effects
				(font
					(size 1.27 1.27)
				)
			)
		)
		(duplicate_pad_numbers_are_jumpers no)
		(fp_line
			(start -0.7874 -0.4064)
			(end 0.7874 -0.4064)
			(stroke
				(width 0.1524)
				(type default)
			)
			(layer "F.SilkS")
		)
		(fp_line
			(start -0.7874 0.4064)
			(end -0.7874 -0.4064)
			(stroke
				(width 0.1524)
				(type default)
			)
			(layer "F.SilkS")
		)
		(fp_line
			(start 0.7874 -0.4064)
			(end 0.7874 0.4064)
			(stroke
				(width 0.1524)
				(type default)
			)
			(layer "F.SilkS")
		)
		(fp_line
			(start 0.7874 0.4064)
			(end -0.7874 0.4064)
			(stroke
				(width 0.1524)
				(type default)
			)
			(layer "F.SilkS")
		)
		(fp_line
			(start -0.67945 -0.305054)
			(end -0.12065 -0.305054)
			(stroke
				(width 0.1)
				(type default)
			)
			(layer "F.Fab")
		)
		(fp_line
			(start -0.67945 0.3048)
			(end -0.67945 -0.305054)
			(stroke
				(width 0.1)
				(type default)
			)
			(layer "F.Fab")
		)
		(fp_line
			(start -0.12065 -0.305054)
			(end -0.12065 -0.2794)
			(stroke
				(width 0.1)
				(type default)
			)
			(layer "F.Fab")
		)
		(fp_line
			(start -0.12065 -0.2794)
			(end 0.12065 -0.2794)
			(stroke
				(width 0.1)
				(type default)
			)
			(layer "F.Fab")
		)
		(fp_line
			(start -0.12065 0.2794)
			(end -0.12065 0.3048)
			(stroke
				(width 0.1)
				(type default)
			)
			(layer "F.Fab")
		)
		(fp_line
			(start -0.12065 0.3048)
			(end -0.67945 0.3048)
			(stroke
				(width 0.1)
				(type default)
			)
			(layer "F.Fab")
		)
		(fp_line
			(start 0.120396 0.2794)
			(end -0.12065 0.2794)
			(stroke
				(width 0.1)
				(type default)
			)
			(layer "F.Fab")
		)
		(fp_line
			(start 0.120396 0.3048)
			(end 0.120396 0.2794)
			(stroke
				(width 0.1)
				(type default)
			)
			(layer "F.Fab")
		)
		(fp_line
			(start 0.12065 -0.3048)
			(end 0.67945 -0.3048)
			(stroke
				(width 0.1)
				(type default)
			)
			(layer "F.Fab")
		)
		(fp_line
			(start 0.12065 -0.2794)
			(end 0.12065 -0.3048)
			(stroke
				(width 0.1)
				(type default)
			)
			(layer "F.Fab")
		)
		(fp_line
			(start 0.67945 -0.3048)
			(end 0.67945 0.3048)
			(stroke
				(width 0.1)
				(type default)
			)
			(layer "F.Fab")
		)
		(fp_line
			(start 0.67945 0.3048)
			(end 0.120396 0.3048)
			(stroke
				(width 0.1)
				(type default)
			)
			(layer "F.Fab")
		)
		(pad "1" smd circle
			(at -0.40005 0)
			(size 0 0)
			(layers "F.Cu" "F.Mask" "F.Paste")
			(net "GND")
		)
		(pad "2" smd circle
			(at 0.40005 0)
			(size 0 0)
			(layers "F.Cu" "F.Mask" "F.Paste")
			(net "PVDDCR_SOC_P1_LSET2")
		)
	)
	(footprint ""
		(layer "F.Cu")
		(at 211.992464 -26.868374 -90)
		(property "Reference" "C1274"
			(at 0 0 270)
			(layer "F.SilkS")
			(hide yes)
			(effects
				(font
					(size 1.27 1.27)
				)
			)
		)
		(property "Value" ""
			(at 0 0 270)
			(layer "F.Fab")
			(effects
				(font
					(size 1.27 1.27)
				)
			)
		)
		(duplicate_pad_numbers_are_jumpers no)
		(fp_line
			(start -0.7874 0.4064)
			(end -0.7874 -0.4064)
			(stroke
				(width 0.1524)
				(type default)
			)
			(layer "F.SilkS")
		)
		(fp_line
			(start 0.7874 0.4064)
			(end -0.7874 0.4064)
			(stroke
				(width 0.1524)
				(type default)
			)
			(layer "F.SilkS")
		)
		(fp_line
			(start -0.7874 -0.4064)
			(end 0.7874 -0.4064)
			(stroke
				(width 0.1524)
				(type default)
			)
			(layer "F.SilkS")
		)
		(fp_line
			(start 0.7874 -0.4064)
			(end 0.7874 0.4064)
			(stroke
				(width 0.1524)
				(type default)
			)
			(layer "F.SilkS")
		)
		(fp_line
			(start -0.67945 0.3048)
			(end -0.67945 -0.305054)
			(stroke
				(width 0.1)
				(type default)
			)
			(layer "F.Fab")
		)
		(fp_line
			(start -0.12065 0.3048)
			(end -0.67945 0.3048)
			(stroke
				(width 0.1)
				(type default)
			)
			(layer "F.Fab")
		)
		(fp_line
			(start 0.120396 0.3048)
			(end 0.120396 0.2794)
			(stroke
				(width 0.1)
				(type default)
			)
			(layer "F.Fab")
		)
		(fp_line
			(start 0.67945 0.3048)
			(end 0.120396 0.3048)
			(stroke
				(width 0.1)
				(type default)
			)
			(layer "F.Fab")
		)
		(fp_line
			(start -0.12065 0.2794)
			(end -0.12065 0.3048)
			(stroke
				(width 0.1)
				(type default)
			)
			(layer "F.Fab")
		)
		(fp_line
			(start 0.120396 0.2794)
			(end -0.12065 0.2794)
			(stroke
				(width 0.1)
				(type default)
			)
			(layer "F.Fab")
		)
		(fp_line
			(start -0.12065 -0.2794)
			(end 0.12065 -0.2794)
			(stroke
				(width 0.1)
				(type default)
			)
			(layer "F.Fab")
		)
		(fp_line
			(start 0.12065 -0.2794)
			(end 0.12065 -0.3048)
			(stroke
				(width 0.1)
				(type default)
			)
			(layer "F.Fab")
		)
		(fp_line
			(start 0.12065 -0.3048)
			(end 0.67945 -0.3048)
			(stroke
				(width 0.1)
				(type default)
			)
			(layer "F.Fab")
		)
		(fp_line
			(start 0.67945 -0.3048)
			(end 0.67945 0.3048)
			(stroke
				(width 0.1)
				(type default)
			)
			(layer "F.Fab")
		)
		(fp_line
			(start -0.67945 -0.305054)
			(end -0.12065 -0.305054)
			(stroke
				(width 0.1)
				(type default)
			)
			(layer "F.Fab")
		)
		(fp_line
			(start -0.12065 -0.305054)
			(end -0.12065 -0.2794)
			(stroke
				(width 0.1)
				(type default)
			)
			(layer "F.Fab")
		)
		(pad "1" smd circle
			(at -0.40005 0 270)
			(size 0 0)
			(layers "F.Cu" "F.Mask" "F.Paste")
			(net "P3V3_AUX")
		)
		(pad "2" smd circle
			(at 0.40005 0 270)
			(size 0 0)
			(layers "F.Cu" "F.Mask" "F.Paste")
			(net "GND")
		)
	)
)
